# S9S_MB_2U (Grand Teton) — schematic netlist excerpt (pin names and nets, part order shuffled) for the footprints in the layout excerpt that follows; sources: Cadence DE-HDL packaged netlist, KiCad conversion of 03242023_DA0F0TMBIJ0_F0T_Motherboard_J_brd_V01_OCP.brd

C283  Q_CAP  22UF 4V 20% X6S  pkg C0402  page 77 : A = PVCCIN_CPU1 ; B = GND

Q88  MOSFET_NCH_DUAL  PJT138K IC  pkg SOT363XD  page 255
  S1  = GND
  G1  = PWRGD_CPUPWRGD_LVC2_R1
  D2  = LED_RST_PLTRST_N_D
  S2  = GND
  G2  = RST_PLTRST_N
  D1  = LED_PWRGD_CPUPWRGD_GTL_D

(kicad_pcb
	(version 20260206)
	(generator "pcbnew")
	(generator_version "10.0")
	(general
		(thickness 1.6)
		(legacy_teardrops no)
	)
	(paper "A4")
	(title_block
		(title "03242023_DA0F0TMBIJ0_F0T_Motherboard_J_brd_V01_OCP.brd")
		(comment 1 "Grand Teton / footprints 1000-1001 of 6105")
	)
	(layers
		(0 "F.Cu" signal "TOP")
		(4 "In1.Cu" signal "GND")
		(6 "In2.Cu" signal "IN1")
		(8 "In3.Cu" signal "GND1")
		(10 "In4.Cu" signal "IN2")
		(12 "In5.Cu" signal "GND2")
		(14 "In6.Cu" signal "IN3")
		(16 "In7.Cu" signal "GND3")
		(18 "In8.Cu" signal "VCC")
		(20 "In9.Cu" signal "VCC1")
		(22 "In10.Cu" signal "GND4")
		(24 "In11.Cu" signal "IN4")
		(26 "In12.Cu" signal "GND5")
		(28 "In13.Cu" signal "IN5")
		(30 "In14.Cu" signal "GND6")
		(32 "In15.Cu" signal "IN6")
		(34 "In16.Cu" signal "GND7")
		(2 "B.Cu" signal "BOTTOM")
		(9 "F.Adhes" user "F.Adhesive")
		(11 "B.Adhes" user "B.Adhesive")
		(13 "F.Paste" user "Package Geometry/Pastemask Top")
		(15 "B.Paste" user "Package Geometry/Pastemask Bottom")
		(5 "F.SilkS" user "Ref Des/Silkscreen Top")
		(7 "B.SilkS" user "Ref Des/Silkscreen Bottom")
		(1 "F.Mask" user "Board Geometry/Soldermask Top")
		(3 "B.Mask" user "Board Geometry/Soldermask Bottom")
		(17 "Dwgs.User" user "User.Drawings")
		(19 "Cmts.User" user "User.Comments")
		(21 "Eco1.User" user "User.Eco1")
		(23 "Eco2.User" user "User.Eco2")
		(25 "Edge.Cuts" user "Board Geometry/Outline")
		(27 "Margin" user)
		(31 "F.CrtYd" user "Package Geometry/Place Bound Top")
		(29 "B.CrtYd" user "Package Geometry/Place Bound Bottom")
		(35 "F.Fab" user "Ref Des/Assembly Top")
		(33 "B.Fab" user "Ref Des/Assembly Bottom")
	)
	(footprint ""
		(layer "F.Cu")
		(at 100.92182 -99.423982)
		(property "Reference" "Q88"
			(at 1.62814 -0.742188 0)
			(unlocked yes)
			(layer "F.SilkS")
			(effects
				(font
					(size 0.7874 0.5842)
					(thickness 0.1524)
				)
				(justify left)
			)
		)
		(property "Value" ""
			(at 0 0 0)
			(layer "F.Fab")
			(effects
				(font
					(size 1.27 1.27)
				)
			)
		)
		(duplicate_pad_numbers_are_jumpers no)
		(fp_line
			(start -1.332738 -1.100074)
			(end -0.4826 -1.100074)
			(stroke
				(width 0.1524)
				(type default)
			)
			(layer "F.SilkS")
		)
		(fp_line
			(start -1.332738 1.100074)
			(end -1.332738 -1.100074)
			(stroke
				(width 0.1524)
				(type default)
			)
			(layer "F.SilkS")
		)
		(fp_line
			(start -0.4826 -1.100074)
			(end 0 -0.541274)
			(stroke
				(width 0.1524)
				(type default)
			)
			(layer "F.SilkS")
		)
		(fp_line
			(start 0 -0.541274)
			(end 0.4826 -1.100074)
			(stroke
				(width 0.1524)
				(type default)
			)
			(layer "F.SilkS")
		)
		(fp_line
			(start 0.4826 -1.100074)
			(end 1.332738 -1.100074)
			(stroke
				(width 0.1524)
				(type default)
			)
			(layer "F.SilkS")
		)
		(fp_line
			(start 1.332738 -1.100074)
			(end 1.332738 1.100074)
			(stroke
				(width 0.1524)
				(type default)
			)
			(layer "F.SilkS")
		)
		(fp_line
			(start 1.332738 1.100074)
			(end -1.332738 1.100074)
			(stroke
				(width 0.1524)
				(type default)
			)
			(layer "F.SilkS")
		)
		(fp_poly
			(pts
				(xy -0.588772 -1.917446) (xy -0.9398 -1.21539) (xy -1.290828 -1.917446)
			)
			(stroke
				(width 0)
				(type default)
			)
			(fill yes)
			(layer "F.SilkS")
		)
		(fp_line
			(start -0.674878 -1.100074)
			(end 0.674878 -1.100074)
			(stroke
				(width 0.1)
				(type default)
			)
			(layer "F.Fab")
		)
		(fp_line
			(start -0.674878 1.100074)
			(end -0.674878 -1.100074)
			(stroke
				(width 0.1)
				(type default)
			)
			(layer "F.Fab")
		)
		(fp_line
			(start 0.674878 -1.100074)
			(end 0.674878 1.100074)
			(stroke
				(width 0.1)
				(type default)
			)
			(layer "F.Fab")
		)
		(fp_line
			(start 0.674878 1.100074)
			(end -0.674878 1.100074)
			(stroke
				(width 0.1)
				(type default)
			)
			(layer "F.Fab")
		)
		(fp_poly
			(pts
				(xy -2.2352 -0.298958) (xy -2.2352 -1.001014) (xy -1.533144 -0.649986)
			)
			(stroke
				(width 0)
				(type default)
			)
			(fill yes)
			(layer "F.Fab")
		)
		(pad "1" smd rect
			(at -0.94996 -0.649986 90)
			(size 0.4318 0.508)
			(layers "F.Cu" "F.Mask" "F.Paste")
			(net "GND")
		)
		(pad "2" smd rect
			(at -0.94996 0 90)
			(size 0.4318 0.508)
			(layers "F.Cu" "F.Mask" "F.Paste")
			(net "PWRGD_CPUPWRGD_LVC2_R1")
		)
		(pad "3" smd rect
			(at -0.94996 0.649986 90)
			(size 0.4318 0.508)
			(layers "F.Cu" "F.Mask" "F.Paste")
			(net "LED_RST_PLTRST_N_D")
		)
		(pad "4" smd rect
			(at 0.94996 0.649986 90)
			(size 0.4318 0.508)
			(layers "F.Cu" "F.Mask" "F.Paste")
			(net "GND")
		)
		(pad "5" smd rect
			(at 0.94996 0 90)
			(size 0.4318 0.508)
			(layers "F.Cu" "F.Mask" "F.Paste")
			(net "RST_PLTRST_N")
		)
		(pad "6" smd rect
			(at 0.94996 -0.649986 90)
			(size 0.4318 0.508)
			(layers "F.Cu" "F.Mask" "F.Paste")
			(net "LED_PWRGD_CPUPWRGD_GTL_D")
		)
	)
	(footprint ""
		(layer "F.Cu")
		(at 106.3117 -255.0541 90)
		(property "Reference" "C283"
			(at 0 0 90)
			(layer "F.SilkS")
			(hide yes)
			(effects
				(font
					(size 1.27 1.27)
				)
			)
		)
		(property "Value" ""
			(at 0 0 90)
			(layer "F.Fab")
			(effects
				(font
					(size 1.27 1.27)
				)
			)
		)
		(duplicate_pad_numbers_are_jumpers no)
		(fp_line
			(start 0.7874 -0.4064)
			(end 0.7874 0.4064)
			(stroke
				(width 0.1524)
				(type default)
			)
			(layer "F.SilkS")
		)
		(fp_line
			(start -0.7874 -0.4064)
			(end 0.7874 -0.4064)
			(stroke
				(width 0.1524)
				(type default)
			)
			(layer "F.SilkS")
		)
		(fp_line
			(start 0.7874 0.4064)
			(end -0.7874 0.4064)
			(stroke
				(width 0.1524)
				(type default)
			)
			(layer "F.SilkS")
		)
		(fp_line
			(start -0.7874 0.4064)
			(end -0.7874 -0.4064)
			(stroke
				(width 0.1524)
				(type default)
			)
			(layer "F.SilkS")
		)
		(fp_line
			(start -0.12065 -0.305054)
			(end -0.12065 -0.2794)
			(stroke
				(width 0.1)
				(type default)
			)
			(layer "F.Fab")
		)
		(fp_line
			(start -0.67945 -0.305054)
			(end -0.12065 -0.305054)
			(stroke
				(width 0.1)
				(type default)
			)
			(layer "F.Fab")
		)
		(fp_line
			(start 0.67945 -0.3048)
			(end 0.67945 0.3048)
			(stroke
				(width 0.1)
				(type default)
			)
			(layer "F.Fab")
		)
		(fp_line
			(start 0.12065 -0.3048)
			(end 0.67945 -0.3048)
			(stroke
				(width 0.1)
				(type default)
			)
			(layer "F.Fab")
		)
		(fp_line
			(start 0.12065 -0.2794)
			(end 0.12065 -0.3048)
			(stroke
				(width 0.1)
				(type default)
			)
			(layer "F.Fab")
		)
		(fp_line
			(start -0.12065 -0.2794)
			(end 0.12065 -0.2794)
			(stroke
				(width 0.1)
				(type default)
			)
			(layer "F.Fab")
		)
		(fp_line
			(start 0.120396 0.2794)
			(end -0.12065 0.2794)
			(stroke
				(width 0.1)
				(type default)
			)
			(layer "F.Fab")
		)
		(fp_line
			(start -0.12065 0.2794)
			(end -0.12065 0.3048)
			(stroke
				(width 0.1)
				(type default)
			)
			(layer "F.Fab")
		)
		(fp_line
			(start 0.67945 0.3048)
			(end 0.120396 0.3048)
			(stroke
				(width 0.1)
				(type default)
			)
			(layer "F.Fab")
		)
		(fp_line
			(start 0.120396 0.3048)
			(end 0.120396 0.2794)
			(stroke
				(width 0.1)
				(type default)
			)
			(layer "F.Fab")
		)
		(fp_line
			(start -0.12065 0.3048)
			(end -0.67945 0.3048)
			(stroke
				(width 0.1)
				(type default)
			)
			(layer "F.Fab")
		)
		(fp_line
			(start -0.67945 0.3048)
			(end -0.67945 -0.305054)
			(stroke
				(width 0.1)
				(type default)
			)
			(layer "F.Fab")
		)
		(pad "1" smd circle
			(at -0.40005 0 90)
			(size 0 0)
			(layers "F.Cu" "F.Mask" "F.Paste")
			(net "PVCCIN_CPU1")
		)
		(pad "2" smd circle
			(at 0.40005 0 90)
			(size 0 0)
			(layers "F.Cu" "F.Mask" "F.Paste")
			(net "GND")
		)
	)
)
